# T6G (Grand Teton) — schematic netlist excerpt (pin names and nets, part order shuffled) for the footprints in the layout excerpt that follows; sources: Cadence DE-HDL packaged netlist, KiCad conversion of 04192023_DAF0TMB3IC0_F0TG_MB_C_brd_V02_OCP.brd

R700  Q_RES  30K 1% EMPTY  pkg 0402LF  page 169 : A = P12V_AUX ; B = P12V_AUX_DSC_VOL
R1311  Q_RES  33 5% CHIP  pkg 0402LF  page 155 : A = IRQ_WAKE_R_N ; B = IRQ_WAKE_N

(kicad_pcb
	(version 20260206)
	(generator "pcbnew")
	(generator_version "10.0")
	(general
		(thickness 1.6)
		(legacy_teardrops no)
	)
	(paper "A4")
	(title_block
		(title "04192023_DAF0TMB3IC0_F0TG_MB_C_brd_V02_OCP.brd")
		(comment 1 "Grand Teton / footprints 3672-3673 of 8354")
	)
	(layers
		(0 "F.Cu" signal "TOP")
		(4 "In1.Cu" signal "GND")
		(6 "In2.Cu" signal "IN1")
		(8 "In3.Cu" signal "GND1")
		(10 "In4.Cu" signal "IN2")
		(12 "In5.Cu" signal "GND2")
		(14 "In6.Cu" signal "IN3")
		(16 "In7.Cu" signal "GND3")
		(18 "In8.Cu" signal "VCC")
		(20 "In9.Cu" signal "VCC1")
		(22 "In10.Cu" signal "GND4")
		(24 "In11.Cu" signal "IN4")
		(26 "In12.Cu" signal "GND5")
		(28 "In13.Cu" signal "IN5")
		(30 "In14.Cu" signal "GND6")
		(32 "In15.Cu" signal "IN6")
		(34 "In16.Cu" signal "GND7")
		(2 "B.Cu" signal "BOTTOM")
		(9 "F.Adhes" user "F.Adhesive")
		(11 "B.Adhes" user "B.Adhesive")
		(13 "F.Paste" user "Package Geometry/Pastemask Top")
		(15 "B.Paste" user "Package Geometry/Pastemask Bottom")
		(5 "F.SilkS" user "Ref Des/Silkscreen Top")
		(7 "B.SilkS" user "Ref Des/Silkscreen Bottom")
		(1 "F.Mask" user "Board Geometry/Soldermask Top")
		(3 "B.Mask" user "Board Geometry/Soldermask Bottom")
		(17 "Dwgs.User" user "User.Drawings")
		(19 "Cmts.User" user "User.Comments")
		(21 "Eco1.User" user "User.Eco1")
		(23 "Eco2.User" user "User.Eco2")
		(25 "Edge.Cuts" user "Board Geometry/Outline")
		(27 "Margin" user)
		(31 "F.CrtYd" user "Package Geometry/Place Bound Top")
		(29 "B.CrtYd" user "Package Geometry/Place Bound Bottom")
		(35 "F.Fab" user "Ref Des/Assembly Top")
		(33 "B.Fab" user "Ref Des/Assembly Bottom")
	)
	(footprint ""
		(layer "F.Cu")
		(at 43.1419 -100.34016 180)
		(property "Reference" "R700"
			(at 0 0 180)
			(layer "F.SilkS")
			(hide yes)
			(effects
				(font
					(size 1.27 1.27)
				)
			)
		)
		(property "Value" ""
			(at 0 0 180)
			(layer "F.Fab")
			(effects
				(font
					(size 1.27 1.27)
				)
			)
		)
		(duplicate_pad_numbers_are_jumpers no)
		(fp_line
			(start 0.7874 0.4064)
			(end -0.7874 0.4064)
			(stroke
				(width 0.1524)
				(type default)
			)
			(layer "F.SilkS")
		)
		(fp_line
			(start 0.7874 -0.4064)
			(end 0.7874 0.4064)
			(stroke
				(width 0.1524)
				(type default)
			)
			(layer "F.SilkS")
		)
		(fp_line
			(start -0.7874 0.4064)
			(end -0.7874 -0.4064)
			(stroke
				(width 0.1524)
				(type default)
			)
			(layer "F.SilkS")
		)
		(fp_line
			(start -0.7874 -0.4064)
			(end 0.7874 -0.4064)
			(stroke
				(width 0.1524)
				(type default)
			)
			(layer "F.SilkS")
		)
		(fp_line
			(start 0.67945 0.3048)
			(end 0.120396 0.3048)
			(stroke
				(width 0.1)
				(type default)
			)
			(layer "F.Fab")
		)
		(fp_line
			(start 0.67945 -0.3048)
			(end 0.67945 0.3048)
			(stroke
				(width 0.1)
				(type default)
			)
			(layer "F.Fab")
		)
		(fp_line
			(start 0.12065 -0.2794)
			(end 0.12065 -0.3048)
			(stroke
				(width 0.1)
				(type default)
			)
			(layer "F.Fab")
		)
		(fp_line
			(start 0.12065 -0.3048)
			(end 0.67945 -0.3048)
			(stroke
				(width 0.1)
				(type default)
			)
			(layer "F.Fab")
		)
		(fp_line
			(start 0.120396 0.3048)
			(end 0.120396 0.2794)
			(stroke
				(width 0.1)
				(type default)
			)
			(layer "F.Fab")
		)
		(fp_line
			(start 0.120396 0.2794)
			(end -0.12065 0.2794)
			(stroke
				(width 0.1)
				(type default)
			)
			(layer "F.Fab")
		)
		(fp_line
			(start -0.12065 0.3048)
			(end -0.67945 0.3048)
			(stroke
				(width 0.1)
				(type default)
			)
			(layer "F.Fab")
		)
		(fp_line
			(start -0.12065 0.2794)
			(end -0.12065 0.3048)
			(stroke
				(width 0.1)
				(type default)
			)
			(layer "F.Fab")
		)
		(fp_line
			(start -0.12065 -0.2794)
			(end 0.12065 -0.2794)
			(stroke
				(width 0.1)
				(type default)
			)
			(layer "F.Fab")
		)
		(fp_line
			(start -0.12065 -0.305054)
			(end -0.12065 -0.2794)
			(stroke
				(width 0.1)
				(type default)
			)
			(layer "F.Fab")
		)
		(fp_line
			(start -0.67945 0.3048)
			(end -0.67945 -0.305054)
			(stroke
				(width 0.1)
				(type default)
			)
			(layer "F.Fab")
		)
		(fp_line
			(start -0.67945 -0.305054)
			(end -0.12065 -0.305054)
			(stroke
				(width 0.1)
				(type default)
			)
			(layer "F.Fab")
		)
		(pad "1" smd circle
			(at -0.40005 0 180)
			(size 0 0)
			(layers "F.Cu" "F.Mask" "F.Paste")
			(net "P12V_AUX")
		)
		(pad "2" smd circle
			(at 0.40005 0 180)
			(size 0 0)
			(layers "F.Cu" "F.Mask" "F.Paste")
			(net "P12V_AUX_DSC_VOL")
		)
	)
	(footprint ""
		(layer "F.Cu")
		(at 160.40227 -73.24217 -90)
		(property "Reference" "R1311"
			(at 0 0 270)
			(layer "F.SilkS")
			(hide yes)
			(effects
				(font
					(size 1.27 1.27)
				)
			)
		)
		(property "Value" ""
			(at 0 0 270)
			(layer "F.Fab")
			(effects
				(font
					(size 1.27 1.27)
				)
			)
		)
		(duplicate_pad_numbers_are_jumpers no)
		(fp_line
			(start -0.7874 0.4064)
			(end -0.7874 -0.4064)
			(stroke
				(width 0.1524)
				(type default)
			)
			(layer "F.SilkS")
		)
		(fp_line
			(start 0.7874 0.4064)
			(end -0.7874 0.4064)
			(stroke
				(width 0.1524)
				(type default)
			)
			(layer "F.SilkS")
		)
		(fp_line
			(start -0.7874 -0.4064)
			(end 0.7874 -0.4064)
			(stroke
				(width 0.1524)
				(type default)
			)
			(layer "F.SilkS")
		)
		(fp_line
			(start 0.7874 -0.4064)
			(end 0.7874 0.4064)
			(stroke
				(width 0.1524)
				(type default)
			)
			(layer "F.SilkS")
		)
		(fp_line
			(start -0.67945 0.3048)
			(end -0.67945 -0.305054)
			(stroke
				(width 0.1)
				(type default)
			)
			(layer "F.Fab")
		)
		(fp_line
			(start -0.12065 0.3048)
			(end -0.67945 0.3048)
			(stroke
				(width 0.1)
				(type default)
			)
			(layer "F.Fab")
		)
		(fp_line
			(start 0.120396 0.3048)
			(end 0.120396 0.2794)
			(stroke
				(width 0.1)
				(type default)
			)
			(layer "F.Fab")
		)
		(fp_line
			(start 0.67945 0.3048)
			(end 0.120396 0.3048)
			(stroke
				(width 0.1)
				(type default)
			)
			(layer "F.Fab")
		)
		(fp_line
			(start -0.12065 0.2794)
			(end -0.12065 0.3048)
			(stroke
				(width 0.1)
				(type default)
			)
			(layer "F.Fab")
		)
		(fp_line
			(start 0.120396 0.2794)
			(end -0.12065 0.2794)
			(stroke
				(width 0.1)
				(type default)
			)
			(layer "F.Fab")
		)
		(fp_line
			(start -0.12065 -0.2794)
			(end 0.12065 -0.2794)
			(stroke
				(width 0.1)
				(type default)
			)
			(layer "F.Fab")
		)
		(fp_line
			(start 0.12065 -0.2794)
			(end 0.12065 -0.3048)
			(stroke
				(width 0.1)
				(type default)
			)
			(layer "F.Fab")
		)
		(fp_line
			(start 0.12065 -0.3048)
			(end 0.67945 -0.3048)
			(stroke
				(width 0.1)
				(type default)
			)
			(layer "F.Fab")
		)
		(fp_line
			(start 0.67945 -0.3048)
			(end 0.67945 0.3048)
			(stroke
				(width 0.1)
				(type default)
			)
			(layer "F.Fab")
		)
		(fp_line
			(start -0.67945 -0.305054)
			(end -0.12065 -0.305054)
			(stroke
				(width 0.1)
				(type default)
			)
			(layer "F.Fab")
		)
		(fp_line
			(start -0.12065 -0.305054)
			(end -0.12065 -0.2794)
			(stroke
				(width 0.1)
				(type default)
			)
			(layer "F.Fab")
		)
		(pad "1" smd circle
			(at -0.40005 0 270)
			(size 0 0)
			(layers "F.Cu" "F.Mask" "F.Paste")
			(net "IRQ_WAKE_R_N")
		)
		(pad "2" smd circle
			(at 0.40005 0 270)
			(size 0 0)
			(layers "F.Cu" "F.Mask" "F.Paste")
			(net "IRQ_WAKE_N")
		)
	)
)
